(kicad_pcb
	(version 20260206)
	(generator "pcbnew")
	(generator_version "10.0")
	(general
		(thickness 1.6)
		(legacy_teardrops no)
	)
	(paper "A4")
	(title_block
		(title "03242023_DA0F0TMBIJ0_F0T_Motherboard_J_brd_V01_OCP.brd")
		(comment 1 "Grand Teton / footprints 2864-2871 of 6105")
	)
	(layers
		(0 "F.Cu" signal "TOP")
		(4 "In1.Cu" signal "GND")
		(6 "In2.Cu" signal "IN1")
		(8 "In3.Cu" signal "GND1")
		(10 "In4.Cu" signal "IN2")
		(12 "In5.Cu" signal "GND2")
		(14 "In6.Cu" signal "IN3")
		(16 "In7.Cu" signal "GND3")
		(18 "In8.Cu" signal "VCC")
		(20 "In9.Cu" signal "VCC1")
		(22 "In10.Cu" signal "GND4")
		(24 "In11.Cu" signal "IN4")
		(26 "In12.Cu" signal "GND5")
		(28 "In13.Cu" signal "IN5")
		(30 "In14.Cu" signal "GND6")
		(32 "In15.Cu" signal "IN6")
		(34 "In16.Cu" signal "GND7")
		(2 "B.Cu" signal "BOTTOM")
		(9 "F.Adhes" user "F.Adhesive")
		(11 "B.Adhes" user "B.Adhesive")
		(13 "F.Paste" user "Package Geometry/Pastemask Top")
		(15 "B.Paste" user "Package Geometry/Pastemask Bottom")
		(5 "F.SilkS" user "Ref Des/Silkscreen Top")
		(7 "B.SilkS" user "Ref Des/Silkscreen Bottom")
		(1 "F.Mask" user "Board Geometry/Soldermask Top")
		(3 "B.Mask" user "Board Geometry/Soldermask Bottom")
		(17 "Dwgs.User" user "User.Drawings")
		(19 "Cmts.User" user "User.Comments")
		(21 "Eco1.User" user "User.Eco1")
		(23 "Eco2.User" user "User.Eco2")
		(25 "Edge.Cuts" user "Board Geometry/Outline")
		(27 "Margin" user)
		(31 "F.CrtYd" user "Package Geometry/Place Bound Top")
		(29 "B.CrtYd" user "Package Geometry/Place Bound Bottom")
		(35 "F.Fab" user "Ref Des/Assembly Top")
		(33 "B.Fab" user "Ref Des/Assembly Bottom")
	)
	(footprint ""
		(layer "F.Cu")
		(at 179.342288 -406.898602)
		(property "Reference" "R3933"
			(at 0 0 0)
			(layer "F.SilkS")
			(hide yes)
			(effects
				(font
					(size 1.27 1.27)
				)
			)
		)
		(property "Value" ""
			(at 0 0 0)
			(layer "F.Fab")
			(effects
				(font
					(size 1.27 1.27)
				)
			)
		)
		(duplicate_pad_numbers_are_jumpers no)
		(fp_line
			(start -0.7874 -0.4064)
			(end 0.7874 -0.4064)
			(stroke
				(width 0.1524)
				(type default)
			)
			(layer "F.SilkS")
		)
		(fp_line
			(start -0.7874 0.4064)
			(end -0.7874 -0.4064)
			(stroke
				(width 0.1524)
				(type default)
			)
			(layer "F.SilkS")
		)
		(fp_line
			(start 0.7874 -0.4064)
			(end 0.7874 0.4064)
			(stroke
				(width 0.1524)
				(type default)
			)
			(layer "F.SilkS")
		)
		(fp_line
			(start 0.7874 0.4064)
			(end -0.7874 0.4064)
			(stroke
				(width 0.1524)
				(type default)
			)
			(layer "F.SilkS")
		)
		(fp_line
			(start -0.67945 -0.305054)
			(end -0.12065 -0.305054)
			(stroke
				(width 0.1)
				(type default)
			)
			(layer "F.Fab")
		)
		(fp_line
			(start -0.67945 0.3048)
			(end -0.67945 -0.305054)
			(stroke
				(width 0.1)
				(type default)
			)
			(layer "F.Fab")
		)
		(fp_line
			(start -0.12065 -0.305054)
			(end -0.12065 -0.2794)
			(stroke
				(width 0.1)
				(type default)
			)
			(layer "F.Fab")
		)
		(fp_line
			(start -0.12065 -0.2794)
			(end 0.12065 -0.2794)
			(stroke
				(width 0.1)
				(type default)
			)
			(layer "F.Fab")
		)
		(fp_line
			(start -0.12065 0.2794)
			(end -0.12065 0.3048)
			(stroke
				(width 0.1)
				(type default)
			)
			(layer "F.Fab")
		)
		(fp_line
			(start -0.12065 0.3048)
			(end -0.67945 0.3048)
			(stroke
				(width 0.1)
				(type default)
			)
			(layer "F.Fab")
		)
		(fp_line
			(start 0.120396 0.2794)
			(end -0.12065 0.2794)
			(stroke
				(width 0.1)
				(type default)
			)
			(layer "F.Fab")
		)
		(fp_line
			(start 0.120396 0.3048)
			(end 0.120396 0.2794)
			(stroke
				(width 0.1)
				(type default)
			)
			(layer "F.Fab")
		)
		(fp_line
			(start 0.12065 -0.3048)
			(end 0.67945 -0.3048)
			(stroke
				(width 0.1)
				(type default)
			)
			(layer "F.Fab")
		)
		(fp_line
			(start 0.12065 -0.2794)
			(end 0.12065 -0.3048)
			(stroke
				(width 0.1)
				(type default)
			)
			(layer "F.Fab")
		)
		(fp_line
			(start 0.67945 -0.3048)
			(end 0.67945 0.3048)
			(stroke
				(width 0.1)
				(type default)
			)
			(layer "F.Fab")
		)
		(fp_line
			(start 0.67945 0.3048)
			(end 0.120396 0.3048)
			(stroke
				(width 0.1)
				(type default)
			)
			(layer "F.Fab")
		)
		(pad "1" smd circle
			(at -0.40005 0)
			(size 0 0)
			(layers "F.Cu" "F.Mask" "F.Paste")
			(net "P12V_AUX")
		)
		(pad "2" smd circle
			(at 0.40005 0)
			(size 0 0)
			(layers "F.Cu" "F.Mask" "F.Paste")
			(net "MB0_P12V_STBY_PWRGD")
		)
	)
	(footprint ""
		(layer "F.Cu")
		(at 189.65037 -427.319948 180)
		(property "Reference" "C1797"
			(at 0 0 180)
			(layer "F.SilkS")
			(hide yes)
			(effects
				(font
					(size 1.27 1.27)
				)
			)
		)
		(property "Value" ""
			(at 0 0 180)
			(layer "F.Fab")
			(effects
				(font
					(size 1.27 1.27)
				)
			)
		)
		(duplicate_pad_numbers_are_jumpers no)
		(fp_line
			(start 0.7874 0.4064)
			(end -0.7874 0.4064)
			(stroke
				(width 0.1524)
				(type default)
			)
			(layer "F.SilkS")
		)
		(fp_line
			(start 0.7874 -0.4064)
			(end 0.7874 0.4064)
			(stroke
				(width 0.1524)
				(type default)
			)
			(layer "F.SilkS")
		)
		(fp_line
			(start -0.7874 0.4064)
			(end -0.7874 -0.4064)
			(stroke
				(width 0.1524)
				(type default)
			)
			(layer "F.SilkS")
		)
		(fp_line
			(start -0.7874 -0.4064)
			(end 0.7874 -0.4064)
			(stroke
				(width 0.1524)
				(type default)
			)
			(layer "F.SilkS")
		)
		(fp_line
			(start 0.67945 0.3048)
			(end 0.120396 0.3048)
			(stroke
				(width 0.1)
				(type default)
			)
			(layer "F.Fab")
		)
		(fp_line
			(start 0.67945 -0.3048)
			(end 0.67945 0.3048)
			(stroke
				(width 0.1)
				(type default)
			)
			(layer "F.Fab")
		)
		(fp_line
			(start 0.12065 -0.2794)
			(end 0.12065 -0.3048)
			(stroke
				(width 0.1)
				(type default)
			)
			(layer "F.Fab")
		)
		(fp_line
			(start 0.12065 -0.3048)
			(end 0.67945 -0.3048)
			(stroke
				(width 0.1)
				(type default)
			)
			(layer "F.Fab")
		)
		(fp_line
			(start 0.120396 0.3048)
			(end 0.120396 0.2794)
			(stroke
				(width 0.1)
				(type default)
			)
			(layer "F.Fab")
		)
		(fp_line
			(start 0.120396 0.2794)
			(end -0.12065 0.2794)
			(stroke
				(width 0.1)
				(type default)
			)
			(layer "F.Fab")
		)
		(fp_line
			(start -0.12065 0.3048)
			(end -0.67945 0.3048)
			(stroke
				(width 0.1)
				(type default)
			)
			(layer "F.Fab")
		)
		(fp_line
			(start -0.12065 0.2794)
			(end -0.12065 0.3048)
			(stroke
				(width 0.1)
				(type default)
			)
			(layer "F.Fab")
		)
		(fp_line
			(start -0.12065 -0.2794)
			(end 0.12065 -0.2794)
			(stroke
				(width 0.1)
				(type default)
			)
			(layer "F.Fab")
		)
		(fp_line
			(start -0.12065 -0.305054)
			(end -0.12065 -0.2794)
			(stroke
				(width 0.1)
				(type default)
			)
			(layer "F.Fab")
		)
		(fp_line
			(start -0.67945 0.3048)
			(end -0.67945 -0.305054)
			(stroke
				(width 0.1)
				(type default)
			)
			(layer "F.Fab")
		)
		(fp_line
			(start -0.67945 -0.305054)
			(end -0.12065 -0.305054)
			(stroke
				(width 0.1)
				(type default)
			)
			(layer "F.Fab")
		)
		(pad "1" smd circle
			(at -0.40005 0 180)
			(size 0 0)
			(layers "F.Cu" "F.Mask" "F.Paste")
			(net "PDB_PRSNT_N")
		)
		(pad "2" smd circle
			(at 0.40005 0 180)
			(size 0 0)
			(layers "F.Cu" "F.Mask" "F.Paste")
			(net "GND")
		)
	)
	(footprint ""
		(layer "F.Cu")
		(at 351.806764 -360.934762 90)
		(property "Reference" "C3266"
			(at 0 0 90)
			(layer "F.SilkS")
			(hide yes)
			(effects
				(font
					(size 1.27 1.27)
				)
			)
		)
		(property "Value" ""
			(at 0 0 90)
			(layer "F.Fab")
			(effects
				(font
					(size 1.27 1.27)
				)
			)
		)
		(duplicate_pad_numbers_are_jumpers no)
		(fp_line
			(start 0.7874 -0.4064)
			(end 0.7874 0.4064)
			(stroke
				(width 0.1524)
				(type default)
			)
			(layer "F.SilkS")
		)
		(fp_line
			(start -0.7874 -0.4064)
			(end 0.7874 -0.4064)
			(stroke
				(width 0.1524)
				(type default)
			)
			(layer "F.SilkS")
		)
		(fp_line
			(start 0.7874 0.4064)
			(end -0.7874 0.4064)
			(stroke
				(width 0.1524)
				(type default)
			)
			(layer "F.SilkS")
		)
		(fp_line
			(start -0.7874 0.4064)
			(end -0.7874 -0.4064)
			(stroke
				(width 0.1524)
				(type default)
			)
			(layer "F.SilkS")
		)
		(fp_line
			(start -0.12065 -0.305054)
			(end -0.12065 -0.2794)
			(stroke
				(width 0.1)
				(type default)
			)
			(layer "F.Fab")
		)
		(fp_line
			(start -0.67945 -0.305054)
			(end -0.12065 -0.305054)
			(stroke
				(width 0.1)
				(type default)
			)
			(layer "F.Fab")
		)
		(fp_line
			(start 0.67945 -0.3048)
			(end 0.67945 0.3048)
			(stroke
				(width 0.1)
				(type default)
			)
			(layer "F.Fab")
		)
		(fp_line
			(start 0.12065 -0.3048)
			(end 0.67945 -0.3048)
			(stroke
				(width 0.1)
				(type default)
			)
			(layer "F.Fab")
		)
		(fp_line
			(start 0.12065 -0.2794)
			(end 0.12065 -0.3048)
			(stroke
				(width 0.1)
				(type default)
			)
			(layer "F.Fab")
		)
		(fp_line
			(start -0.12065 -0.2794)
			(end 0.12065 -0.2794)
			(stroke
				(width 0.1)
				(type default)
			)
			(layer "F.Fab")
		)
		(fp_line
			(start 0.120396 0.2794)
			(end -0.12065 0.2794)
			(stroke
				(width 0.1)
				(type default)
			)
			(layer "F.Fab")
		)
		(fp_line
			(start -0.12065 0.2794)
			(end -0.12065 0.3048)
			(stroke
				(width 0.1)
				(type default)
			)
			(layer "F.Fab")
		)
		(fp_line
			(start 0.67945 0.3048)
			(end 0.120396 0.3048)
			(stroke
				(width 0.1)
				(type default)
			)
			(layer "F.Fab")
		)
		(fp_line
			(start 0.120396 0.3048)
			(end 0.120396 0.2794)
			(stroke
				(width 0.1)
				(type default)
			)
			(layer "F.Fab")
		)
		(fp_line
			(start -0.12065 0.3048)
			(end -0.67945 0.3048)
			(stroke
				(width 0.1)
				(type default)
			)
			(layer "F.Fab")
		)
		(fp_line
			(start -0.67945 0.3048)
			(end -0.67945 -0.305054)
			(stroke
				(width 0.1)
				(type default)
			)
			(layer "F.Fab")
		)
		(pad "1" smd circle
			(at -0.40005 0 90)
			(size 0 0)
			(layers "F.Cu" "F.Mask" "F.Paste")
			(net "PWRGD_PVCCIN_CPU0_R")
		)
		(pad "2" smd circle
			(at 0.40005 0 90)
			(size 0 0)
			(layers "F.Cu" "F.Mask" "F.Paste")
			(net "GND")
		)
	)
	(footprint ""
		(layer "F.Cu")
		(at 422.55694 -101.270308 -90)
		(property "Reference" "PR3844"
			(at 0 0 270)
			(layer "F.SilkS")
			(hide yes)
			(effects
				(font
					(size 1.27 1.27)
				)
			)
		)
		(property "Value" ""
			(at 0 0 270)
			(layer "F.Fab")
			(effects
				(font
					(size 1.27 1.27)
				)
			)
		)
		(duplicate_pad_numbers_are_jumpers no)
		(fp_line
			(start -0.7874 0.4064)
			(end -0.7874 -0.4064)
			(stroke
				(width 0.1524)
				(type default)
			)
			(layer "F.SilkS")
		)
		(fp_line
			(start 0.7874 0.4064)
			(end -0.7874 0.4064)
			(stroke
				(width 0.1524)
				(type default)
			)
			(layer "F.SilkS")
		)
		(fp_line
			(start -0.7874 -0.4064)
			(end 0.7874 -0.4064)
			(stroke
				(width 0.1524)
				(type default)
			)
			(layer "F.SilkS")
		)
		(fp_line
			(start 0.7874 -0.4064)
			(end 0.7874 0.4064)
			(stroke
				(width 0.1524)
				(type default)
			)
			(layer "F.SilkS")
		)
		(fp_line
			(start -0.67945 0.3048)
			(end -0.67945 -0.305054)
			(stroke
				(width 0.1)
				(type default)
			)
			(layer "F.Fab")
		)
		(fp_line
			(start -0.12065 0.3048)
			(end -0.67945 0.3048)
			(stroke
				(width 0.1)
				(type default)
			)
			(layer "F.Fab")
		)
		(fp_line
			(start 0.120396 0.3048)
			(end 0.120396 0.2794)
			(stroke
				(width 0.1)
				(type default)
			)
			(layer "F.Fab")
		)
		(fp_line
			(start 0.67945 0.3048)
			(end 0.120396 0.3048)
			(stroke
				(width 0.1)
				(type default)
			)
			(layer "F.Fab")
		)
		(fp_line
			(start -0.12065 0.2794)
			(end -0.12065 0.3048)
			(stroke
				(width 0.1)
				(type default)
			)
			(layer "F.Fab")
		)
		(fp_line
			(start 0.120396 0.2794)
			(end -0.12065 0.2794)
			(stroke
				(width 0.1)
				(type default)
			)
			(layer "F.Fab")
		)
		(fp_line
			(start -0.12065 -0.2794)
			(end 0.12065 -0.2794)
			(stroke
				(width 0.1)
				(type default)
			)
			(layer "F.Fab")
		)
		(fp_line
			(start 0.12065 -0.2794)
			(end 0.12065 -0.3048)
			(stroke
				(width 0.1)
				(type default)
			)
			(layer "F.Fab")
		)
		(fp_line
			(start 0.12065 -0.3048)
			(end 0.67945 -0.3048)
			(stroke
				(width 0.1)
				(type default)
			)
			(layer "F.Fab")
		)
		(fp_line
			(start 0.67945 -0.3048)
			(end 0.67945 0.3048)
			(stroke
				(width 0.1)
				(type default)
			)
			(layer "F.Fab")
		)
		(fp_line
			(start -0.67945 -0.305054)
			(end -0.12065 -0.305054)
			(stroke
				(width 0.1)
				(type default)
			)
			(layer "F.Fab")
		)
		(fp_line
			(start -0.12065 -0.305054)
			(end -0.12065 -0.2794)
			(stroke
				(width 0.1)
				(type default)
			)
			(layer "F.Fab")
		)
		(pad "1" smd circle
			(at -0.40005 0 270)
			(size 0 0)
			(layers "F.Cu" "F.Mask" "F.Paste")
			(net "P3V3_OCP_MODE_1")
		)
		(pad "2" smd circle
			(at 0.40005 0 270)
			(size 0 0)
			(layers "F.Cu" "F.Mask" "F.Paste")
			(net "GND")
		)
	)
	(footprint ""
		(layer "F.Cu")
		(at 372.31193 -402.371052 -90)
		(property "Reference" "C935"
			(at 0 0 270)
			(layer "F.SilkS")
			(hide yes)
			(effects
				(font
					(size 1.27 1.27)
				)
			)
		)
		(property "Value" ""
			(at 0 0 270)
			(layer "F.Fab")
			(effects
				(font
					(size 1.27 1.27)
				)
			)
		)
		(duplicate_pad_numbers_are_jumpers no)
		(fp_line
			(start -0.299974 0.150114)
			(end -0.299974 -0.150114)
			(stroke
				(width 0.1)
				(type default)
			)
			(layer "F.Fab")
		)
		(fp_line
			(start 0.299974 0.150114)
			(end -0.299974 0.150114)
			(stroke
				(width 0.1)
				(type default)
			)
			(layer "F.Fab")
		)
		(fp_line
			(start -0.299974 -0.150114)
			(end 0.299974 -0.150114)
			(stroke
				(width 0.1)
				(type default)
			)
			(layer "F.Fab")
		)
		(fp_line
			(start 0.299974 -0.150114)
			(end 0.299974 0.150114)
			(stroke
				(width 0.1)
				(type default)
			)
			(layer "F.Fab")
		)
		(pad "1" smd rect
			(at -0.2667 0 270)
			(size 0.3048 0.381)
			(layers "F.Cu" "F.Mask" "F.Paste")
			(net "P5E_CPU0_PE2_TX_C_DP<15>")
		)
		(pad "2" smd rect
			(at 0.2667 0 270)
			(size 0.3048 0.381)
			(layers "F.Cu" "F.Mask" "F.Paste")
			(net "P5E_CPU0_PE2_TX_DP<15>")
		)
	)
	(footprint ""
		(layer "F.Cu")
		(at 64.616838 -408.517344 -90)
		(property "Reference" "C698"
			(at 0 0 270)
			(layer "F.SilkS")
			(hide yes)
			(effects
				(font
					(size 1.27 1.27)
				)
			)
		)
		(property "Value" ""
			(at 0 0 270)
			(layer "F.Fab")
			(effects
				(font
					(size 1.27 1.27)
				)
			)
		)
		(duplicate_pad_numbers_are_jumpers no)
		(fp_line
			(start -0.299974 0.150114)
			(end -0.299974 -0.150114)
			(stroke
				(width 0.1)
				(type default)
			)
			(layer "F.Fab")
		)
		(fp_line
			(start 0.299974 0.150114)
			(end -0.299974 0.150114)
			(stroke
				(width 0.1)
				(type default)
			)
			(layer "F.Fab")
		)
		(fp_line
			(start -0.299974 -0.150114)
			(end 0.299974 -0.150114)
			(stroke
				(width 0.1)
				(type default)
			)
			(layer "F.Fab")
		)
		(fp_line
			(start 0.299974 -0.150114)
			(end 0.299974 0.150114)
			(stroke
				(width 0.1)
				(type default)
			)
			(layer "F.Fab")
		)
		(pad "1" smd rect
			(at -0.2667 0 270)
			(size 0.3048 0.381)
			(layers "F.Cu" "F.Mask" "F.Paste")
			(net "P5E_CPU1_PE4_TX_C_DN<5>")
		)
		(pad "2" smd rect
			(at 0.2667 0 270)
			(size 0.3048 0.381)
			(layers "F.Cu" "F.Mask" "F.Paste")
			(net "P5E_CPU1_PE4_TX_DN<5>")
		)
	)
	(footprint ""
		(layer "F.Cu")
		(at 237.171738 -119.183658 -90)
		(property "Reference" "R3196"
			(at 0 0 270)
			(layer "F.SilkS")
			(hide yes)
			(effects
				(font
					(size 1.27 1.27)
				)
			)
		)
		(property "Value" ""
			(at 0 0 270)
			(layer "F.Fab")
			(effects
				(font
					(size 1.27 1.27)
				)
			)
		)
		(duplicate_pad_numbers_are_jumpers no)
		(fp_line
			(start -0.7874 0.4064)
			(end -0.7874 -0.064262)
			(stroke
				(width 0.1524)
				(type default)
			)
			(layer "F.SilkS")
		)
		(fp_line
			(start 0.7874 0.4064)
			(end -0.7874 0.4064)
			(stroke
				(width 0.1524)
				(type default)
			)
			(layer "F.SilkS")
		)
		(fp_line
			(start 0.7874 -0.016002)
			(end 0.7874 0.4064)
			(stroke
				(width 0.1524)
				(type default)
			)
			(layer "F.SilkS")
		)
		(fp_line
			(start -0.287782 -0.4064)
			(end 0.438658 -0.4064)
			(stroke
				(width 0.1524)
				(type default)
			)
			(layer "F.SilkS")
		)
		(fp_line
			(start -0.67945 0.3048)
			(end -0.67945 -0.305054)
			(stroke
				(width 0.1)
				(type default)
			)
			(layer "F.Fab")
		)
		(fp_line
			(start -0.12065 0.3048)
			(end -0.67945 0.3048)
			(stroke
				(width 0.1)
				(type default)
			)
			(layer "F.Fab")
		)
		(fp_line
			(start 0.120396 0.3048)
			(end 0.120396 0.2794)
			(stroke
				(width 0.1)
				(type default)
			)
			(layer "F.Fab")
		)
		(fp_line
			(start 0.67945 0.3048)
			(end 0.120396 0.3048)
			(stroke
				(width 0.1)
				(type default)
			)
			(layer "F.Fab")
		)
		(fp_line
			(start -0.12065 0.2794)
			(end -0.12065 0.3048)
			(stroke
				(width 0.1)
				(type default)
			)
			(layer "F.Fab")
		)
		(fp_line
			(start 0.120396 0.2794)
			(end -0.12065 0.2794)
			(stroke
				(width 0.1)
				(type default)
			)
			(layer "F.Fab")
		)
		(fp_line
			(start -0.12065 -0.2794)
			(end 0.12065 -0.2794)
			(stroke
				(width 0.1)
				(type default)
			)
			(layer "F.Fab")
		)
		(fp_line
			(start 0.12065 -0.2794)
			(end 0.12065 -0.3048)
			(stroke
				(width 0.1)
				(type default)
			)
			(layer "F.Fab")
		)
		(fp_line
			(start 0.12065 -0.3048)
			(end 0.67945 -0.3048)
			(stroke
				(width 0.1)
				(type default)
			)
			(layer "F.Fab")
		)
		(fp_line
			(start 0.67945 -0.3048)
			(end 0.67945 0.3048)
			(stroke
				(width 0.1)
				(type default)
			)
			(layer "F.Fab")
		)
		(fp_line
			(start -0.67945 -0.305054)
			(end -0.12065 -0.305054)
			(stroke
				(width 0.1)
				(type default)
			)
			(layer "F.Fab")
		)
		(fp_line
			(start -0.12065 -0.305054)
			(end -0.12065 -0.2794)
			(stroke
				(width 0.1)
				(type default)
			)
			(layer "F.Fab")
		)
		(pad "1" smd circle
			(at -0.40005 0 270)
			(size 0 0)
			(layers "F.Cu" "F.Mask" "F.Paste")
			(net "CLK_100M_OCP_V3_2_B_R_DP")
		)
		(pad "2" smd circle
			(at 0.40005 0 270)
			(size 0 0)
			(layers "F.Cu" "F.Mask" "F.Paste")
			(net "CLK_100M_OCP_V3_2_B_DP")
		)
	)
	(footprint ""
		(layer "F.Cu")
		(at 138.508994 -402.371052 -90)
		(property "Reference" "C755"
			(at 0 0 270)
			(layer "F.SilkS")
			(hide yes)
			(effects
				(font
					(size 1.27 1.27)
				)
			)
		)
		(property "Value" ""
			(at 0 0 270)
			(layer "F.Fab")
			(effects
				(font
					(size 1.27 1.27)
				)
			)
		)
		(duplicate_pad_numbers_are_jumpers no)
		(fp_line
			(start -0.299974 0.150114)
			(end -0.299974 -0.150114)
			(stroke
				(width 0.1)
				(type default)
			)
			(layer "F.Fab")
		)
		(fp_line
			(start 0.299974 0.150114)
			(end -0.299974 0.150114)
			(stroke
				(width 0.1)
				(type default)
			)
			(layer "F.Fab")
		)
		(fp_line
			(start -0.299974 -0.150114)
			(end 0.299974 -0.150114)
			(stroke
				(width 0.1)
				(type default)
			)
			(layer "F.Fab")
		)
		(fp_line
			(start 0.299974 -0.150114)
			(end 0.299974 0.150114)
			(stroke
				(width 0.1)
				(type default)
			)
			(layer "F.Fab")
		)
		(pad "1" smd rect
			(at -0.2667 0 270)
			(size 0.3048 0.381)
			(layers "F.Cu" "F.Mask" "F.Paste")
			(net "P5E_CPU1_PE2_TX_C_DP<9>")
		)
		(pad "2" smd rect
			(at 0.2667 0 270)
			(size 0.3048 0.381)
			(layers "F.Cu" "F.Mask" "F.Paste")
			(net "P5E_CPU1_PE2_TX_DP<9>")
		)
	)
)
